# T6G (Grand Teton) — schematic netlist excerpt (pin names and nets, part order shuffled) for the footprints in the layout excerpt that follows; sources: Cadence DE-HDL packaged netlist, KiCad conversion of 04192023_DAF0TMB3IC0_F0TG_MB_C_brd_V02_OCP.brd

PC476  Q_CAP  2.2UF 10V 10% X6S  pkg C0402  page 194 : A = PVDDCR_CPU0_P0_VCC2 ; B = GND
C229  Q_CAP  100UF 4V 20% X6S  pkg C0805  page 323 : A = P0V9_CPU1_RT_2D ; B = GND
R490  Q_RES  0 5% EMPTY  pkg 0402LF  page 188 : A = PWRGD_P5V_R ; B = SW_P3V3_EN_R

(kicad_pcb
	(version 20260206)
	(generator "pcbnew")
	(generator_version "10.0")
	(general
		(thickness 1.6)
		(legacy_teardrops no)
	)
	(paper "A4")
	(title_block
		(title "04192023_DAF0TMB3IC0_F0TG_MB_C_brd_V02_OCP.brd")
		(comment 1 "Grand Teton / footprints 3504-3506 of 8354")
	)
	(layers
		(0 "F.Cu" signal "TOP")
		(4 "In1.Cu" signal "GND")
		(6 "In2.Cu" signal "IN1")
		(8 "In3.Cu" signal "GND1")
		(10 "In4.Cu" signal "IN2")
		(12 "In5.Cu" signal "GND2")
		(14 "In6.Cu" signal "IN3")
		(16 "In7.Cu" signal "GND3")
		(18 "In8.Cu" signal "VCC")
		(20 "In9.Cu" signal "VCC1")
		(22 "In10.Cu" signal "GND4")
		(24 "In11.Cu" signal "IN4")
		(26 "In12.Cu" signal "GND5")
		(28 "In13.Cu" signal "IN5")
		(30 "In14.Cu" signal "GND6")
		(32 "In15.Cu" signal "IN6")
		(34 "In16.Cu" signal "GND7")
		(2 "B.Cu" signal "BOTTOM")
		(9 "F.Adhes" user "F.Adhesive")
		(11 "B.Adhes" user "B.Adhesive")
		(13 "F.Paste" user "Package Geometry/Pastemask Top")
		(15 "B.Paste" user "Package Geometry/Pastemask Bottom")
		(5 "F.SilkS" user "Ref Des/Silkscreen Top")
		(7 "B.SilkS" user "Ref Des/Silkscreen Bottom")
		(1 "F.Mask" user "Board Geometry/Soldermask Top")
		(3 "B.Mask" user "Board Geometry/Soldermask Bottom")
		(17 "Dwgs.User" user "User.Drawings")
		(19 "Cmts.User" user "User.Comments")
		(21 "Eco1.User" user "User.Eco1")
		(23 "Eco2.User" user "User.Eco2")
		(25 "Edge.Cuts" user "Board Geometry/Outline")
		(27 "Margin" user)
		(31 "F.CrtYd" user "Package Geometry/Place Bound Top")
		(29 "B.CrtYd" user "Package Geometry/Place Bound Bottom")
		(35 "F.Fab" user "Ref Des/Assembly Top")
		(33 "B.Fab" user "Ref Des/Assembly Bottom")
	)
	(footprint ""
		(layer "F.Cu")
		(at 205.232 -131.064)
		(property "Reference" "R490"
			(at 0 0 0)
			(layer "F.SilkS")
			(hide yes)
			(effects
				(font
					(size 1.27 1.27)
				)
			)
		)
		(property "Value" ""
			(at 0 0 0)
			(layer "F.Fab")
			(effects
				(font
					(size 1.27 1.27)
				)
			)
		)
		(duplicate_pad_numbers_are_jumpers no)
		(fp_line
			(start -0.7874 -0.4064)
			(end 0.7874 -0.4064)
			(stroke
				(width 0.1524)
				(type default)
			)
			(layer "F.SilkS")
		)
		(fp_line
			(start -0.7874 0.4064)
			(end -0.7874 -0.4064)
			(stroke
				(width 0.1524)
				(type default)
			)
			(layer "F.SilkS")
		)
		(fp_line
			(start 0.7874 -0.4064)
			(end 0.7874 0.4064)
			(stroke
				(width 0.1524)
				(type default)
			)
			(layer "F.SilkS")
		)
		(fp_line
			(start 0.7874 0.4064)
			(end -0.7874 0.4064)
			(stroke
				(width 0.1524)
				(type default)
			)
			(layer "F.SilkS")
		)
		(fp_line
			(start -0.67945 -0.305054)
			(end -0.12065 -0.305054)
			(stroke
				(width 0.1)
				(type default)
			)
			(layer "F.Fab")
		)
		(fp_line
			(start -0.67945 0.3048)
			(end -0.67945 -0.305054)
			(stroke
				(width 0.1)
				(type default)
			)
			(layer "F.Fab")
		)
		(fp_line
			(start -0.12065 -0.305054)
			(end -0.12065 -0.2794)
			(stroke
				(width 0.1)
				(type default)
			)
			(layer "F.Fab")
		)
		(fp_line
			(start -0.12065 -0.2794)
			(end 0.12065 -0.2794)
			(stroke
				(width 0.1)
				(type default)
			)
			(layer "F.Fab")
		)
		(fp_line
			(start -0.12065 0.2794)
			(end -0.12065 0.3048)
			(stroke
				(width 0.1)
				(type default)
			)
			(layer "F.Fab")
		)
		(fp_line
			(start -0.12065 0.3048)
			(end -0.67945 0.3048)
			(stroke
				(width 0.1)
				(type default)
			)
			(layer "F.Fab")
		)
		(fp_line
			(start 0.120396 0.2794)
			(end -0.12065 0.2794)
			(stroke
				(width 0.1)
				(type default)
			)
			(layer "F.Fab")
		)
		(fp_line
			(start 0.120396 0.3048)
			(end 0.120396 0.2794)
			(stroke
				(width 0.1)
				(type default)
			)
			(layer "F.Fab")
		)
		(fp_line
			(start 0.12065 -0.3048)
			(end 0.67945 -0.3048)
			(stroke
				(width 0.1)
				(type default)
			)
			(layer "F.Fab")
		)
		(fp_line
			(start 0.12065 -0.2794)
			(end 0.12065 -0.3048)
			(stroke
				(width 0.1)
				(type default)
			)
			(layer "F.Fab")
		)
		(fp_line
			(start 0.67945 -0.3048)
			(end 0.67945 0.3048)
			(stroke
				(width 0.1)
				(type default)
			)
			(layer "F.Fab")
		)
		(fp_line
			(start 0.67945 0.3048)
			(end 0.120396 0.3048)
			(stroke
				(width 0.1)
				(type default)
			)
			(layer "F.Fab")
		)
		(pad "1" smd circle
			(at -0.40005 0)
			(size 0 0)
			(layers "F.Cu" "F.Mask" "F.Paste")
			(net "PWRGD_P5V_R")
		)
		(pad "2" smd circle
			(at 0.40005 0)
			(size 0 0)
			(layers "F.Cu" "F.Mask" "F.Paste")
			(net "SW_P3V3_EN_R")
		)
	)
	(footprint ""
		(layer "F.Cu")
		(at 376.35815 -180.078634 -90)
		(property "Reference" "PC476"
			(at 0 0 270)
			(layer "F.SilkS")
			(hide yes)
			(effects
				(font
					(size 1.27 1.27)
				)
			)
		)
		(property "Value" ""
			(at 0 0 270)
			(layer "F.Fab")
			(effects
				(font
					(size 1.27 1.27)
				)
			)
		)
		(duplicate_pad_numbers_are_jumpers no)
		(fp_line
			(start -0.7874 0.4064)
			(end -0.7874 -0.4064)
			(stroke
				(width 0.1524)
				(type default)
			)
			(layer "F.SilkS")
		)
		(fp_line
			(start -0.210566 0.4064)
			(end -0.7874 0.4064)
			(stroke
				(width 0.1524)
				(type default)
			)
			(layer "F.SilkS")
		)
		(fp_line
			(start 0.7874 0.4064)
			(end 0.399034 0.4064)
			(stroke
				(width 0.1524)
				(type default)
			)
			(layer "F.SilkS")
		)
		(fp_line
			(start -0.7874 -0.4064)
			(end 0.7874 -0.4064)
			(stroke
				(width 0.1524)
				(type default)
			)
			(layer "F.SilkS")
		)
		(fp_line
			(start 0.7874 -0.4064)
			(end 0.7874 0.4064)
			(stroke
				(width 0.1524)
				(type default)
			)
			(layer "F.SilkS")
		)
		(fp_line
			(start -0.67945 0.3048)
			(end -0.67945 -0.305054)
			(stroke
				(width 0.1)
				(type default)
			)
			(layer "F.Fab")
		)
		(fp_line
			(start -0.12065 0.3048)
			(end -0.67945 0.3048)
			(stroke
				(width 0.1)
				(type default)
			)
			(layer "F.Fab")
		)
		(fp_line
			(start 0.120396 0.3048)
			(end 0.120396 0.2794)
			(stroke
				(width 0.1)
				(type default)
			)
			(layer "F.Fab")
		)
		(fp_line
			(start 0.67945 0.3048)
			(end 0.120396 0.3048)
			(stroke
				(width 0.1)
				(type default)
			)
			(layer "F.Fab")
		)
		(fp_line
			(start -0.12065 0.2794)
			(end -0.12065 0.3048)
			(stroke
				(width 0.1)
				(type default)
			)
			(layer "F.Fab")
		)
		(fp_line
			(start 0.120396 0.2794)
			(end -0.12065 0.2794)
			(stroke
				(width 0.1)
				(type default)
			)
			(layer "F.Fab")
		)
		(fp_line
			(start -0.12065 -0.2794)
			(end 0.12065 -0.2794)
			(stroke
				(width 0.1)
				(type default)
			)
			(layer "F.Fab")
		)
		(fp_line
			(start 0.12065 -0.2794)
			(end 0.12065 -0.3048)
			(stroke
				(width 0.1)
				(type default)
			)
			(layer "F.Fab")
		)
		(fp_line
			(start 0.12065 -0.3048)
			(end 0.67945 -0.3048)
			(stroke
				(width 0.1)
				(type default)
			)
			(layer "F.Fab")
		)
		(fp_line
			(start 0.67945 -0.3048)
			(end 0.67945 0.3048)
			(stroke
				(width 0.1)
				(type default)
			)
			(layer "F.Fab")
		)
		(fp_line
			(start -0.67945 -0.305054)
			(end -0.12065 -0.305054)
			(stroke
				(width 0.1)
				(type default)
			)
			(layer "F.Fab")
		)
		(fp_line
			(start -0.12065 -0.305054)
			(end -0.12065 -0.2794)
			(stroke
				(width 0.1)
				(type default)
			)
			(layer "F.Fab")
		)
		(pad "1" smd circle
			(at -0.40005 0 270)
			(size 0 0)
			(layers "F.Cu" "F.Mask" "F.Paste")
			(net "PVDDCR_CPU0_P0_VCC2")
		)
		(pad "2" smd circle
			(at 0.40005 0 270)
			(size 0 0)
			(layers "F.Cu" "F.Mask" "F.Paste")
			(net "GND")
		)
	)
	(footprint ""
		(layer "F.Cu")
		(at 48.523652 -400.419316 -90)
		(property "Reference" "C229"
			(at 0 0 270)
			(layer "F.SilkS")
			(hide yes)
			(effects
				(font
					(size 1.27 1.27)
				)
			)
		)
		(property "Value" ""
			(at 0 0 270)
			(layer "F.Fab")
			(effects
				(font
					(size 1.27 1.27)
				)
			)
		)
		(duplicate_pad_numbers_are_jumpers no)
		(fp_line
			(start -1.524 0.762)
			(end -1.524 -0.762)
			(stroke
				(width 0.1524)
				(type default)
			)
			(layer "F.SilkS")
		)
		(fp_line
			(start 1.524 0.762)
			(end -1.524 0.762)
			(stroke
				(width 0.1524)
				(type default)
			)
			(layer "F.SilkS")
		)
		(fp_line
			(start -1.524 -0.762)
			(end 1.524 -0.762)
			(stroke
				(width 0.1524)
				(type default)
			)
			(layer "F.SilkS")
		)
		(fp_line
			(start 1.524 -0.762)
			(end 1.524 0.762)
			(stroke
				(width 0.1524)
				(type default)
			)
			(layer "F.SilkS")
		)
		(fp_line
			(start -1.1049 0.724916)
			(end 1.1049 0.724916)
			(stroke
				(width 0.1)
				(type default)
			)
			(layer "F.Fab")
		)
		(fp_line
			(start 1.1049 0.724916)
			(end 1.1049 -0.724916)
			(stroke
				(width 0.1)
				(type default)
			)
			(layer "F.Fab")
		)
		(fp_line
			(start -1.1049 -0.724916)
			(end -1.1049 0.724916)
			(stroke
				(width 0.1)
				(type default)
			)
			(layer "F.Fab")
		)
		(fp_line
			(start 1.1049 -0.724916)
			(end -1.1049 -0.724916)
			(stroke
				(width 0.1)
				(type default)
			)
			(layer "F.Fab")
		)
		(pad "1" smd rect
			(at -0.889 0 90)
			(size 1.016 1.27)
			(layers "F.Cu" "F.Mask" "F.Paste")
			(net "P0V9_CPU1_RT_2D")
		)
		(pad "2" smd rect
			(at 0.889 0 90)
			(size 1.016 1.27)
			(layers "F.Cu" "F.Mask" "F.Paste")
			(net "GND")
		)
	)
)
